# S9S_MB_2U (Grand Teton) — schematic netlist excerpt (pin names and nets, part order shuffled) for the footprints in the layout excerpt that follows; sources: Cadence DE-HDL packaged netlist, KiCad conversion of 03242023_DA0F0TMBIJ0_F0T_Motherboard_J_brd_V01_OCP.brd

R772  Q_RES  1K 1% CHIP  pkg 0402LF  page 131 : A = JTAG_RST_DBP_RSMRST_N ; B = RST_RSMRST_PCH_N
R3173  Q_RES  1K 1% CHIP  pkg 0402LF  page 159 : A = SGPIO_OCP_V3_2_LD_N ; B = P3V3_OCP_V3_2
C10  Q_CAP  10UF 16V 10% X6S  pkg C0805  page 84 : A = P12V_S3_AUX_CPU0_NVDIMM ; B = GND

(kicad_pcb
	(version 20260206)
	(generator "pcbnew")
	(generator_version "10.0")
	(general
		(thickness 1.6)
		(legacy_teardrops no)
	)
	(paper "A4")
	(title_block
		(title "03242023_DA0F0TMBIJ0_F0T_Motherboard_J_brd_V01_OCP.brd")
		(comment 1 "Grand Teton / footprints 5347-5349 of 6105")
	)
	(layers
		(0 "F.Cu" signal "TOP")
		(4 "In1.Cu" signal "GND")
		(6 "In2.Cu" signal "IN1")
		(8 "In3.Cu" signal "GND1")
		(10 "In4.Cu" signal "IN2")
		(12 "In5.Cu" signal "GND2")
		(14 "In6.Cu" signal "IN3")
		(16 "In7.Cu" signal "GND3")
		(18 "In8.Cu" signal "VCC")
		(20 "In9.Cu" signal "VCC1")
		(22 "In10.Cu" signal "GND4")
		(24 "In11.Cu" signal "IN4")
		(26 "In12.Cu" signal "GND5")
		(28 "In13.Cu" signal "IN5")
		(30 "In14.Cu" signal "GND6")
		(32 "In15.Cu" signal "IN6")
		(34 "In16.Cu" signal "GND7")
		(2 "B.Cu" signal "BOTTOM")
		(9 "F.Adhes" user "F.Adhesive")
		(11 "B.Adhes" user "B.Adhesive")
		(13 "F.Paste" user "Package Geometry/Pastemask Top")
		(15 "B.Paste" user "Package Geometry/Pastemask Bottom")
		(5 "F.SilkS" user "Ref Des/Silkscreen Top")
		(7 "B.SilkS" user "Ref Des/Silkscreen Bottom")
		(1 "F.Mask" user "Board Geometry/Soldermask Top")
		(3 "B.Mask" user "Board Geometry/Soldermask Bottom")
		(17 "Dwgs.User" user "User.Drawings")
		(19 "Cmts.User" user "User.Comments")
		(21 "Eco1.User" user "User.Eco1")
		(23 "Eco2.User" user "User.Eco2")
		(25 "Edge.Cuts" user "Board Geometry/Outline")
		(27 "Margin" user)
		(31 "F.CrtYd" user "Package Geometry/Place Bound Top")
		(29 "B.CrtYd" user "Package Geometry/Place Bound Bottom")
		(35 "F.Fab" user "Ref Des/Assembly Top")
		(33 "B.Fab" user "Ref Des/Assembly Bottom")
	)
	(footprint ""
		(layer "B.Cu")
		(at 74.85888 -11.267948 90)
		(property "Reference" "R3173"
			(at 0 0 90)
			(layer "B.SilkS")
			(hide yes)
			(effects
				(font
					(size 1.27 1.27)
				)
				(justify mirror)
			)
		)
		(property "Value" ""
			(at 0 0 90)
			(layer "B.Fab")
			(effects
				(font
					(size 1.27 1.27)
				)
				(justify mirror)
			)
		)
		(duplicate_pad_numbers_are_jumpers no)
		(fp_line
			(start 0.7874 -0.4064)
			(end -0.7874 -0.4064)
			(stroke
				(width 0.1524)
				(type default)
			)
			(layer "B.SilkS")
		)
		(fp_line
			(start -0.7874 -0.4064)
			(end -0.7874 0.4064)
			(stroke
				(width 0.1524)
				(type default)
			)
			(layer "B.SilkS")
		)
		(fp_line
			(start 0.7874 0.4064)
			(end 0.7874 -0.4064)
			(stroke
				(width 0.1524)
				(type default)
			)
			(layer "B.SilkS")
		)
		(fp_line
			(start -0.7874 0.4064)
			(end 0.7874 0.4064)
			(stroke
				(width 0.1524)
				(type default)
			)
			(layer "B.SilkS")
		)
		(fp_line
			(start 0.67945 -0.305054)
			(end 0.12065 -0.305054)
			(stroke
				(width 0.1)
				(type default)
			)
			(layer "B.Fab")
		)
		(fp_line
			(start 0.12065 -0.305054)
			(end 0.12065 -0.2794)
			(stroke
				(width 0.1)
				(type default)
			)
			(layer "B.Fab")
		)
		(fp_line
			(start -0.12065 -0.3048)
			(end -0.67945 -0.3048)
			(stroke
				(width 0.1)
				(type default)
			)
			(layer "B.Fab")
		)
		(fp_line
			(start -0.67945 -0.3048)
			(end -0.67945 0.3048)
			(stroke
				(width 0.1)
				(type default)
			)
			(layer "B.Fab")
		)
		(fp_line
			(start 0.12065 -0.2794)
			(end -0.12065 -0.2794)
			(stroke
				(width 0.1)
				(type default)
			)
			(layer "B.Fab")
		)
		(fp_line
			(start -0.12065 -0.2794)
			(end -0.12065 -0.3048)
			(stroke
				(width 0.1)
				(type default)
			)
			(layer "B.Fab")
		)
		(fp_line
			(start 0.12065 0.2794)
			(end 0.12065 0.3048)
			(stroke
				(width 0.1)
				(type default)
			)
			(layer "B.Fab")
		)
		(fp_line
			(start -0.120396 0.2794)
			(end 0.12065 0.2794)
			(stroke
				(width 0.1)
				(type default)
			)
			(layer "B.Fab")
		)
		(fp_line
			(start 0.67945 0.3048)
			(end 0.67945 -0.305054)
			(stroke
				(width 0.1)
				(type default)
			)
			(layer "B.Fab")
		)
		(fp_line
			(start 0.12065 0.3048)
			(end 0.67945 0.3048)
			(stroke
				(width 0.1)
				(type default)
			)
			(layer "B.Fab")
		)
		(fp_line
			(start -0.120396 0.3048)
			(end -0.120396 0.2794)
			(stroke
				(width 0.1)
				(type default)
			)
			(layer "B.Fab")
		)
		(fp_line
			(start -0.67945 0.3048)
			(end -0.120396 0.3048)
			(stroke
				(width 0.1)
				(type default)
			)
			(layer "B.Fab")
		)
		(pad "1" smd circle
			(at 0.40005 0 270)
			(size 0 0)
			(layers "B.Cu" "B.Mask" "B.Paste")
			(net "SGPIO_OCP_V3_2_LD_N")
		)
		(pad "2" smd circle
			(at -0.40005 0 270)
			(size 0 0)
			(layers "B.Cu" "B.Mask" "B.Paste")
			(net "P3V3_OCP_V3_2")
		)
	)
	(footprint ""
		(layer "B.Cu")
		(at 404.006812 -52.722018 180)
		(property "Reference" "R772"
			(at 0 0 0)
			(layer "B.SilkS")
			(hide yes)
			(effects
				(font
					(size 1.27 1.27)
				)
				(justify mirror)
			)
		)
		(property "Value" ""
			(at 0 0 0)
			(layer "B.Fab")
			(effects
				(font
					(size 1.27 1.27)
				)
				(justify mirror)
			)
		)
		(duplicate_pad_numbers_are_jumpers no)
		(fp_line
			(start 0.7874 0.4064)
			(end 0.7874 -0.4064)
			(stroke
				(width 0.1524)
				(type default)
			)
			(layer "B.SilkS")
		)
		(fp_line
			(start 0.7874 -0.4064)
			(end -0.7874 -0.4064)
			(stroke
				(width 0.1524)
				(type default)
			)
			(layer "B.SilkS")
		)
		(fp_line
			(start -0.7874 0.4064)
			(end 0.7874 0.4064)
			(stroke
				(width 0.1524)
				(type default)
			)
			(layer "B.SilkS")
		)
		(fp_line
			(start -0.7874 -0.4064)
			(end -0.7874 0.4064)
			(stroke
				(width 0.1524)
				(type default)
			)
			(layer "B.SilkS")
		)
		(fp_line
			(start 0.67945 0.3048)
			(end 0.67945 -0.305054)
			(stroke
				(width 0.1)
				(type default)
			)
			(layer "B.Fab")
		)
		(fp_line
			(start 0.67945 -0.305054)
			(end 0.12065 -0.305054)
			(stroke
				(width 0.1)
				(type default)
			)
			(layer "B.Fab")
		)
		(fp_line
			(start 0.12065 0.3048)
			(end 0.67945 0.3048)
			(stroke
				(width 0.1)
				(type default)
			)
			(layer "B.Fab")
		)
		(fp_line
			(start 0.12065 0.2794)
			(end 0.12065 0.3048)
			(stroke
				(width 0.1)
				(type default)
			)
			(layer "B.Fab")
		)
		(fp_line
			(start 0.12065 -0.2794)
			(end -0.12065 -0.2794)
			(stroke
				(width 0.1)
				(type default)
			)
			(layer "B.Fab")
		)
		(fp_line
			(start 0.12065 -0.305054)
			(end 0.12065 -0.2794)
			(stroke
				(width 0.1)
				(type default)
			)
			(layer "B.Fab")
		)
		(fp_line
			(start -0.120396 0.3048)
			(end -0.120396 0.2794)
			(stroke
				(width 0.1)
				(type default)
			)
			(layer "B.Fab")
		)
		(fp_line
			(start -0.120396 0.2794)
			(end 0.12065 0.2794)
			(stroke
				(width 0.1)
				(type default)
			)
			(layer "B.Fab")
		)
		(fp_line
			(start -0.12065 -0.2794)
			(end -0.12065 -0.3048)
			(stroke
				(width 0.1)
				(type default)
			)
			(layer "B.Fab")
		)
		(fp_line
			(start -0.12065 -0.3048)
			(end -0.67945 -0.3048)
			(stroke
				(width 0.1)
				(type default)
			)
			(layer "B.Fab")
		)
		(fp_line
			(start -0.67945 0.3048)
			(end -0.120396 0.3048)
			(stroke
				(width 0.1)
				(type default)
			)
			(layer "B.Fab")
		)
		(fp_line
			(start -0.67945 -0.3048)
			(end -0.67945 0.3048)
			(stroke
				(width 0.1)
				(type default)
			)
			(layer "B.Fab")
		)
		(pad "1" smd circle
			(at 0.40005 0)
			(size 0 0)
			(layers "B.Cu" "B.Mask" "B.Paste")
			(net "JTAG_RST_DBP_RSMRST_N")
		)
		(pad "2" smd circle
			(at -0.40005 0)
			(size 0 0)
			(layers "B.Cu" "B.Mask" "B.Paste")
			(net "RST_RSMRST_PCH_N")
		)
	)
	(footprint ""
		(layer "B.Cu")
		(at 290.332414 -321.549776 -90)
		(property "Reference" "C10"
			(at 0 0 90)
			(layer "B.SilkS")
			(hide yes)
			(effects
				(font
					(size 1.27 1.27)
				)
				(justify mirror)
			)
		)
		(property "Value" ""
			(at 0 0 90)
			(layer "B.Fab")
			(effects
				(font
					(size 1.27 1.27)
				)
				(justify mirror)
			)
		)
		(duplicate_pad_numbers_are_jumpers no)
		(fp_line
			(start -1.524 0.762)
			(end 1.524 0.762)
			(stroke
				(width 0.1524)
				(type default)
			)
			(layer "B.SilkS")
		)
		(fp_line
			(start 1.524 0.762)
			(end 1.524 -0.762)
			(stroke
				(width 0.1524)
				(type default)
			)
			(layer "B.SilkS")
		)
		(fp_line
			(start -1.524 -0.762)
			(end -1.524 0.762)
			(stroke
				(width 0.1524)
				(type default)
			)
			(layer "B.SilkS")
		)
		(fp_line
			(start 1.524 -0.762)
			(end -1.524 -0.762)
			(stroke
				(width 0.1524)
				(type default)
			)
			(layer "B.SilkS")
		)
		(fp_line
			(start -1.1049 0.724916)
			(end -1.1049 -0.724916)
			(stroke
				(width 0.1)
				(type default)
			)
			(layer "B.Fab")
		)
		(fp_line
			(start 1.1049 0.724916)
			(end -1.1049 0.724916)
			(stroke
				(width 0.1)
				(type default)
			)
			(layer "B.Fab")
		)
		(fp_line
			(start -1.1049 -0.724916)
			(end 1.1049 -0.724916)
			(stroke
				(width 0.1)
				(type default)
			)
			(layer "B.Fab")
		)
		(fp_line
			(start 1.1049 -0.724916)
			(end 1.1049 0.724916)
			(stroke
				(width 0.1)
				(type default)
			)
			(layer "B.Fab")
		)
		(pad "1" smd rect
			(at 0.889 0 270)
			(size 1.016 1.27)
			(layers "B.Cu" "B.Mask" "B.Paste")
			(net "P12V_S3_AUX_CPU0_NVDIMM")
		)
		(pad "2" smd rect
			(at -0.889 0 270)
			(size 1.016 1.27)
			(layers "B.Cu" "B.Mask" "B.Paste")
			(net "GND")
		)
	)
)
